# S9S_MB_2U (Grand Teton) — schematic netlist excerpt (pin names and nets, part order shuffled) for the footprints in the layout excerpt that follows; sources: Cadence DE-HDL packaged netlist, KiCad conversion of 03242023_DA0F0TMBIJ0_F0T_Motherboard_J_brd_V01_OCP.brd

J79  PICOPROBE_BXA  DELTA-L 4.0 EMPTY  pkg TRIANG_LAUNCH_3PXB  page 308
  \1_p\  = DELTA_L_85_10INCH_IN3_DP
  \2_n\  = DELTA_L_85_10INCH_IN3_DN
  \3_g\  = DELTA_L_GND_1

(kicad_pcb
	(version 20260206)
	(generator "pcbnew")
	(generator_version "10.0")
	(general
		(thickness 1.6)
		(legacy_teardrops no)
	)
	(paper "A4")
	(title_block
		(title "03242023_DA0F0TMBIJ0_F0T_Motherboard_J_brd_V01_OCP.brd")
		(comment 1 "Grand Teton / footprints 425-425 of 6105")
	)
	(layers
		(0 "F.Cu" signal "TOP")
		(4 "In1.Cu" signal "GND")
		(6 "In2.Cu" signal "IN1")
		(8 "In3.Cu" signal "GND1")
		(10 "In4.Cu" signal "IN2")
		(12 "In5.Cu" signal "GND2")
		(14 "In6.Cu" signal "IN3")
		(16 "In7.Cu" signal "GND3")
		(18 "In8.Cu" signal "VCC")
		(20 "In9.Cu" signal "VCC1")
		(22 "In10.Cu" signal "GND4")
		(24 "In11.Cu" signal "IN4")
		(26 "In12.Cu" signal "GND5")
		(28 "In13.Cu" signal "IN5")
		(30 "In14.Cu" signal "GND6")
		(32 "In15.Cu" signal "IN6")
		(34 "In16.Cu" signal "GND7")
		(2 "B.Cu" signal "BOTTOM")
		(9 "F.Adhes" user "F.Adhesive")
		(11 "B.Adhes" user "B.Adhesive")
		(13 "F.Paste" user "Package Geometry/Pastemask Top")
		(15 "B.Paste" user "Package Geometry/Pastemask Bottom")
		(5 "F.SilkS" user "Ref Des/Silkscreen Top")
		(7 "B.SilkS" user "Ref Des/Silkscreen Bottom")
		(1 "F.Mask" user "Board Geometry/Soldermask Top")
		(3 "B.Mask" user "Board Geometry/Soldermask Bottom")
		(17 "Dwgs.User" user "User.Drawings")
		(19 "Cmts.User" user "User.Comments")
		(21 "Eco1.User" user "User.Eco1")
		(23 "Eco2.User" user "User.Eco2")
		(25 "Edge.Cuts" user "Board Geometry/Outline")
		(27 "Margin" user)
		(31 "F.CrtYd" user "Package Geometry/Place Bound Top")
		(29 "B.CrtYd" user "Package Geometry/Place Bound Bottom")
		(35 "F.Fab" user "Ref Des/Assembly Top")
		(33 "B.Fab" user "Ref Des/Assembly Bottom")
	)
	(footprint ""
		(layer "F.Cu")
		(at 182.14594 2.921)
		(property "Reference" "J79"
			(at -4.31927 1.016 90)
			(unlocked yes)
			(layer "F.SilkS")
			(effects
				(font
					(size 0.7874 0.5842)
					(thickness 0.1524)
				)
				(justify left)
			)
		)
		(property "Value" ""
			(at 0 0 0)
			(layer "F.Fab")
			(effects
				(font
					(size 1.27 1.27)
				)
			)
		)
		(duplicate_pad_numbers_are_jumpers no)
		(fp_line
			(start -1.2192 -2.1082)
			(end 1.2192 -2.1082)
			(stroke
				(width 0.1524)
				(type default)
			)
			(layer "F.SilkS")
		)
		(fp_line
			(start -1.2192 2.1082)
			(end -1.2192 -2.1082)
			(stroke
				(width 0.1524)
				(type default)
			)
			(layer "F.SilkS")
		)
		(fp_line
			(start 1.2192 -2.1082)
			(end 1.2192 2.1082)
			(stroke
				(width 0.1524)
				(type default)
			)
			(layer "F.SilkS")
		)
		(fp_line
			(start 1.2192 2.1082)
			(end -1.2192 2.1082)
			(stroke
				(width 0.1524)
				(type default)
			)
			(layer "F.SilkS")
		)
		(pad "" np_thru_hole circle
			(at -2.8829 -1.27 270)
			(size 1.0414 1.0414)
			(drill 1.0414)
			(layers "*.Cu" "*.Mask")
			(clearance 0.381)
			(thermal_gap 0.381)
		)
		(pad "" np_thru_hole circle
			(at -2.8829 1.27 270)
			(size 1.0414 1.0414)
			(drill 1.0414)
			(layers "*.Cu" "*.Mask")
			(clearance 0.381)
			(thermal_gap 0.381)
		)
		(pad "" np_thru_hole circle
			(at 3.4671 -1.27 270)
			(size 1.0414 1.0414)
			(drill 1.0414)
			(layers "*.Cu" "*.Mask")
			(clearance 0.381)
			(thermal_gap 0.381)
		)
		(pad "" np_thru_hole circle
			(at 3.4671 1.27 270)
			(size 1.0414 1.0414)
			(drill 1.0414)
			(layers "*.Cu" "*.Mask")
			(clearance 0.381)
			(thermal_gap 0.381)
		)
		(pad "1" smd rect
			(at 0.8255 -0.249936 270)
			(size 0.3048 0.508)
			(layers "F.Cu" "F.Mask" "F.Paste")
			(net "DELTA_L_85_10INCH_IN3_DP")
		)
		(pad "2" smd rect
			(at 0.8255 0.249936 270)
			(size 0.3048 0.508)
			(layers "F.Cu" "F.Mask" "F.Paste")
			(net "DELTA_L_85_10INCH_IN3_DN")
		)
		(pad "3" smd circle
			(at 0 0)
			(size 0 0)
			(layers "F.Cu" "F.Mask" "F.Paste")
			(net "DELTA_L_GND_1")
		)
		(zone
			(layer "F.Cu")
			(hatch none 0.5)
			(connect_pads
				(clearance 0)
			)
			(min_thickness 0.25)
			(keepout
				(tracks not_allowed)
				(vias allowed)
				(pads allowed)
				(copperpour not_allowed)
				(footprints allowed)
			)
			(placement
				(enabled no)
				(sheetname "")
			)
			(fill
				(thermal_gap 0.5)
				(thermal_bridge_width 0.5)
				(island_removal_mode 0)
			)
			(polygon
				(pts
					(xy 183.26354 2.37236) (xy 183.26354 2.467864) (xy 182.66664 2.467864) (xy 182.66664 2.874264)
					(xy 183.26354 2.874264) (xy 183.26354 2.967736) (xy 182.66664 2.967736) (xy 182.66664 3.374136)
					(xy 183.26354 3.374136) (xy 183.26354 3.46964) (xy 182.56504 3.46964) (xy 182.56504 2.37236)
				)
			)
		)
		(zone
			(layers "F.Cu" "B.Cu" "In1.Cu" "In2.Cu" "In3.Cu" "In4.Cu" "In5.Cu" "In6.Cu"
				"In7.Cu" "In8.Cu" "In9.Cu" "In10.Cu" "In11.Cu" "In12.Cu" "In13.Cu" "In14.Cu"
				"In15.Cu" "In16.Cu"
			)
			(hatch none 0.5)
			(connect_pads
				(clearance 0)
			)
			(min_thickness 0.25)
			(keepout
				(tracks not_allowed)
				(vias allowed)
				(pads allowed)
				(copperpour not_allowed)
				(footprints allowed)
			)
			(placement
				(enabled no)
				(sheetname "")
			)
			(fill
				(thermal_gap 0.5)
				(thermal_bridge_width 0.5)
				(island_removal_mode 0)
			)
			(polygon
				(pts
					(arc
						(start 180.19014 1.651)
						(mid 178.33594 1.651)
						(end 180.19014 1.651)
					)
				)
			)
		)
		(zone
			(layers "F.Cu" "B.Cu" "In1.Cu" "In2.Cu" "In3.Cu" "In4.Cu" "In5.Cu" "In6.Cu"
				"In7.Cu" "In8.Cu" "In9.Cu" "In10.Cu" "In11.Cu" "In12.Cu" "In13.Cu" "In14.Cu"
				"In15.Cu" "In16.Cu"
			)
			(hatch none 0.5)
			(connect_pads
				(clearance 0)
			)
			(min_thickness 0.25)
			(keepout
				(tracks not_allowed)
				(vias allowed)
				(pads allowed)
				(copperpour not_allowed)
				(footprints allowed)
			)
			(placement
				(enabled no)
				(sheetname "")
			)
			(fill
				(thermal_gap 0.5)
				(thermal_bridge_width 0.5)
				(island_removal_mode 0)
			)
			(polygon
				(pts
					(arc
						(start 180.19014 4.191)
						(mid 178.33594 4.191)
						(end 180.19014 4.191)
					)
				)
			)
		)
		(zone
			(layers "F.Cu" "B.Cu" "In1.Cu" "In2.Cu" "In3.Cu" "In4.Cu" "In5.Cu" "In6.Cu"
				"In7.Cu" "In8.Cu" "In9.Cu" "In10.Cu" "In11.Cu" "In12.Cu" "In13.Cu" "In14.Cu"
				"In15.Cu" "In16.Cu"
			)
			(hatch none 0.5)
			(connect_pads
				(clearance 0)
			)
			(min_thickness 0.25)
			(keepout
				(tracks not_allowed)
				(vias allowed)
				(pads allowed)
				(copperpour not_allowed)
				(footprints allowed)
			)
			(placement
				(enabled no)
				(sheetname "")
			)
			(fill
				(thermal_gap 0.5)
				(thermal_bridge_width 0.5)
				(island_removal_mode 0)
			)
			(polygon
				(pts
					(arc
						(start 186.54014 1.651)
						(mid 184.68594 1.651)
						(end 186.54014 1.651)
					)
				)
			)
		)
		(zone
			(layers "F.Cu" "B.Cu" "In1.Cu" "In2.Cu" "In3.Cu" "In4.Cu" "In5.Cu" "In6.Cu"
				"In7.Cu" "In8.Cu" "In9.Cu" "In10.Cu" "In11.Cu" "In12.Cu" "In13.Cu" "In14.Cu"
				"In15.Cu" "In16.Cu"
			)
			(hatch none 0.5)
			(connect_pads
				(clearance 0)
			)
			(min_thickness 0.25)
			(keepout
				(tracks not_allowed)
				(vias allowed)
				(pads allowed)
				(copperpour not_allowed)
				(footprints allowed)
			)
			(placement
				(enabled no)
				(sheetname "")
			)
			(fill
				(thermal_gap 0.5)
				(thermal_bridge_width 0.5)
				(island_removal_mode 0)
			)
			(polygon
				(pts
					(arc
						(start 186.54014 4.191)
						(mid 184.68594 4.191)
						(end 186.54014 4.191)
					)
				)
			)
		)
	)
)
